(kicad_pcb
	(version 20241229)
	(generator "pcbnew")
	(generator_version "9.0")
	(general
		(thickness 1.59)
		(legacy_teardrops no)
	)
	(paper "A3")
	(title_block
		(title "usb-c-power-adapter")
		(date "2025-06-24")
		(rev "1.1.2")
		(company "Antmicro")
		(comment 9 "footprints 41-44 of 122")
	)
	(layers
		(0 "F.Cu" signal)
		(4 "In1.Cu" signal)
		(6 "In2.Cu" signal)
		(2 "B.Cu" signal)
		(9 "F.Adhes" user "F.Adhesive")
		(11 "B.Adhes" user "B.Adhesive")
		(13 "F.Paste" user)
		(15 "B.Paste" user)
		(5 "F.SilkS" user "F.Silkscreen")
		(7 "B.SilkS" user "B.Silkscreen")
		(1 "F.Mask" user)
		(3 "B.Mask" user)
		(17 "Dwgs.User" user "User.Drawings")
		(19 "Cmts.User" user "User.Comments")
		(21 "Eco1.User" user "User.Eco1")
		(23 "Eco2.User" user "User.Eco2")
		(25 "Edge.Cuts" user)
		(27 "Margin" user)
		(31 "F.CrtYd" user "F.Courtyard")
		(29 "B.CrtYd" user "B.Courtyard")
		(35 "F.Fab" user)
		(33 "B.Fab" user)
	)
	(footprint "antmicro-footprints:QFN-24-1EP_4x4mm_P0.5_EP2.1x2.1mm"
		(layer "F.Cu")
		(at 85.6 73.4 -90)
		(property "Reference" "U1"
			(at -1.8228 2.4404 0)
			(layer "F.SilkS")
			(effects
				(font
					(size 0.7 0.7)
					(thickness 0.15)
				)
				(justify right bottom)
			)
		)
		(property "Value" "STUSB4500_QFN"
			(at 0 3.4 90)
			(layer "F.Fab")
			(effects
				(font
					(size 0.7 0.7)
					(thickness 0.15)
				)
				(justify right bottom)
			)
		)
		(property "Datasheet" "https://www.mouser.com/datasheet/2/389/dm00489312-1799262.pdf"
			(at 0 0 270)
			(layer "F.Fab")
			(hide yes)
			(effects
				(font
					(size 1.27 1.27)
					(thickness 0.15)
				)
			)
		)
		(property "Description" "USB Controller USB 2.0 I2C Interface 24-QFN (4x4)"
			(at 0 0 270)
			(layer "F.Fab")
			(hide yes)
			(effects
				(font
					(size 1.27 1.27)
					(thickness 0.15)
				)
			)
		)
		(property "MPN" "STUSB4500QTR"
			(at 0 0 270)
			(unlocked yes)
			(layer "F.Fab")
			(hide yes)
			(effects
				(font
					(size 1 1)
					(thickness 0.15)
				)
			)
		)
		(property "Manufacturer" "STMicroelectronics"
			(at 0 0 270)
			(unlocked yes)
			(layer "F.Fab")
			(hide yes)
			(effects
				(font
					(size 1 1)
					(thickness 0.15)
				)
			)
		)
		(property "Author" "Antmicro"
			(at 0 0 270)
			(unlocked yes)
			(layer "F.Fab")
			(hide yes)
			(effects
				(font
					(size 1 1)
					(thickness 0.15)
				)
			)
		)
		(property "License" "Apache-2.0"
			(at 0 0 270)
			(unlocked yes)
			(layer "F.Fab")
			(hide yes)
			(effects
				(font
					(size 1 1)
					(thickness 0.15)
				)
			)
		)
		(sheetname "/USB PD/")
		(sheetfile "usb_pd.kicad_sch")
		(attr smd)
		(fp_line
			(start -2.11 2.108)
			(end -2.11 1.634)
			(stroke
				(width 0.15)
				(type solid)
			)
			(layer "F.SilkS")
		)
		(fp_line
			(start -1.635 2.108)
			(end -2.11 2.108)
			(stroke
				(width 0.15)
				(type solid)
			)
			(layer "F.SilkS")
		)
		(fp_line
			(start 1.634 2.108)
			(end 2.108 2.108)
			(stroke
				(width 0.15)
				(type solid)
			)
			(layer "F.SilkS")
		)
		(fp_line
			(start 2.108 2.108)
			(end 2.108 1.634)
			(stroke
				(width 0.15)
				(type solid)
			)
			(layer "F.SilkS")
		)
		(fp_line
			(start -2.11 -1.636)
			(end -2.11 -2.11)
			(stroke
				(width 0.15)
				(type solid)
			)
			(layer "F.SilkS")
		)
		(fp_line
			(start -1.635 -2.11)
			(end -2.11 -2.11)
			(stroke
				(width 0.15)
				(type solid)
			)
			(layer "F.SilkS")
		)
		(fp_line
			(start 1.634 -2.11)
			(end 2.108 -2.11)
			(stroke
				(width 0.15)
				(type solid)
			)
			(layer "F.SilkS")
		)
		(fp_line
			(start 2.108 -2.11)
			(end 2.108 -1.635)
			(stroke
				(width 0.15)
				(type solid)
			)
			(layer "F.SilkS")
		)
		(fp_circle
			(center -2.3 -2.3)
			(end -2.25 -2.3)
			(stroke
				(width 0.15)
				(type solid)
			)
			(fill yes)
			(layer "F.SilkS")
		)
		(fp_rect
			(start -2.503 -2.503)
			(end 2.5 2.5)
			(stroke
				(width 0.05)
				(type solid)
			)
			(fill no)
			(layer "F.CrtYd")
		)
		(fp_line
			(start -2 1.999)
			(end -2 -1)
			(stroke
				(width 0.15)
				(type solid)
			)
			(layer "F.Fab")
		)
		(fp_line
			(start 1.999 1.999)
			(end -2 1.999)
			(stroke
				(width 0.15)
				(type solid)
			)
			(layer "F.Fab")
		)
		(fp_line
			(start -2 -1)
			(end -1 -2)
			(stroke
				(width 0.15)
				(type solid)
			)
			(layer "F.Fab")
		)
		(fp_line
			(start -1 -2)
			(end 1.999 -2)
			(stroke
				(width 0.15)
				(type solid)
			)
			(layer "F.Fab")
		)
		(fp_line
			(start 1.999 -2)
			(end 1.999 1.999)
			(stroke
				(width 0.15)
				(type solid)
			)
			(layer "F.Fab")
		)
		(pad "" smd roundrect
			(at -0.5 -0.5 270)
			(size 0.8 0.8)
			(layers "F.Paste")
			(roundrect_rratio 0.238095)
		)
		(pad "" smd roundrect
			(at -0.5 0.5 270)
			(size 0.8 0.8)
			(layers "F.Paste")
			(roundrect_rratio 0.238095)
		)
		(pad "" smd roundrect
			(at 0.5 -0.5 270)
			(size 0.8 0.8)
			(layers "F.Paste")
			(roundrect_rratio 0.238095)
		)
		(pad "" smd roundrect
			(at 0.5 0.5 270)
			(size 0.8 0.8)
			(layers "F.Paste")
			(roundrect_rratio 0.238095)
		)
		(pad "1" smd roundrect
			(at -1.938 -1.25 270)
			(size 0.825 0.25)
			(layers "F.Cu" "F.Mask" "F.Paste")
			(roundrect_rratio 0.25)
			(net 29 "/USB PD/CC1")
			(pinfunction "CC1DB")
			(pintype "bidirectional")
		)
		(pad "2" smd roundrect
			(at -1.938 -0.75 270)
			(size 0.825 0.25)
			(layers "F.Cu" "F.Mask" "F.Paste")
			(roundrect_rratio 0.25)
			(net 29 "/USB PD/CC1")
			(pinfunction "CC1")
			(pintype "bidirectional")
		)
		(pad "3" smd roundrect
			(at -1.938 -0.25 270)
			(size 0.825 0.25)
			(layers "F.Cu" "F.Mask" "F.Paste")
			(roundrect_rratio 0.25)
			(net 58 "unconnected-(U1-NC-Pad3)")
			(pinfunction "NC")
			(pintype "no_connect")
		)
		(pad "4" smd roundrect
			(at -1.938 0.248 270)
			(size 0.825 0.25)
			(layers "F.Cu" "F.Mask" "F.Paste")
			(roundrect_rratio 0.25)
			(net 33 "/USB PD/CC2")
			(pinfunction "CC2")
			(pintype "bidirectional")
		)
		(pad "5" smd roundrect
			(at -1.938 0.748 270)
			(size 0.825 0.25)
			(layers "F.Cu" "F.Mask" "F.Paste")
			(roundrect_rratio 0.25)
			(net 33 "/USB PD/CC2")
			(pinfunction "CC2DB")
			(pintype "bidirectional")
		)
		(pad "6" smd roundrect
			(at -1.938 1.249 270)
			(size 0.825 0.25)
			(layers "F.Cu" "F.Mask" "F.Paste")
			(roundrect_rratio 0.25)
			(net 42 "Net-(U1-RESET)")
			(pinfunction "RESET")
			(pintype "input")
		)
		(pad "7" smd roundrect
			(at -1.25 1.937 270)
			(size 0.25 0.825)
			(layers "F.Cu" "F.Mask" "F.Paste")
			(roundrect_rratio 0.25)
			(net 38 "/USB PD/SCL")
			(pinfunction "SCL")
			(pintype "input")
		)
		(pad "8" smd roundrect
			(at -0.75 1.937 270)
			(size 0.25 0.825)
			(layers "F.Cu" "F.Mask" "F.Paste")
			(roundrect_rratio 0.25)
			(net 37 "/USB PD/SDA")
			(pinfunction "SDA")
			(pintype "bidirectional")
		)
		(pad "9" smd roundrect
			(at -0.25 1.937 270)
			(size 0.25 0.825)
			(layers "F.Cu" "F.Mask" "F.Paste")
			(roundrect_rratio 0.25)
			(net 41 "Net-(U1-DISCH)")
			(pinfunction "DISCH")
			(pintype "bidirectional")
		)
		(pad "10" smd roundrect
			(at 0.248 1.937 270)
			(size 0.25 0.825)
			(layers "F.Cu" "F.Mask" "F.Paste")
			(roundrect_rratio 0.25)
			(net 2 "GND")
			(pinfunction "GND")
			(pintype "power_in")
		)
		(pad "11" smd roundrect
			(at 0.748 1.937 270)
			(size 0.25 0.825)
			(layers "F.Cu" "F.Mask" "F.Paste")
			(roundrect_rratio 0.25)
			(net 55 "Net-(U1-ATTACH)")
			(pinfunction "ATTACH")
			(pintype "output")
		)
		(pad "12" smd roundrect
			(at 1.249 1.937 270)
			(size 0.25 0.825)
			(layers "F.Cu" "F.Mask" "F.Paste")
			(roundrect_rratio 0.25)
			(net 2 "GND")
			(pinfunction "ADDR0")
			(pintype "input")
		)
		(pad "13" smd roundrect
			(at 1.937 1.249 270)
			(size 0.825 0.25)
			(layers "F.Cu" "F.Mask" "F.Paste")
			(roundrect_rratio 0.25)
			(net 2 "GND")
			(pinfunction "ADDR1")
			(pintype "input")
		)
		(pad "14" smd roundrect
			(at 1.937 0.748 270)
			(size 0.825 0.25)
			(layers "F.Cu" "F.Mask" "F.Paste")
			(roundrect_rratio 0.25)
			(net 28 "POWER_OK3")
			(pinfunction "POWER_OK3")
			(pintype "output")
		)
		(pad "15" smd roundrect
			(at 1.937 0.248 270)
			(size 0.825 0.25)
			(layers "F.Cu" "F.Mask" "F.Paste")
			(roundrect_rratio 0.25)
			(net 57 "Net-(U1-GPIO)")
			(pinfunction "GPIO")
			(pintype "output")
		)
		(pad "16" smd roundrect
			(at 1.937 -0.25 270)
			(size 0.825 0.25)
			(layers "F.Cu" "F.Mask" "F.Paste")
			(roundrect_rratio 0.25)
			(net 53 "/USB PD/VBUS_EN")
			(pinfunction "VBUS_EN_SNK")
			(pintype "output")
		)
		(pad "17" smd roundrect
			(at 1.937 -0.75 270)
			(size 0.825 0.25)
			(layers "F.Cu" "F.Mask" "F.Paste")
			(roundrect_rratio 0.25)
			(net 56 "Net-(U1-A_B_SIDE)")
			(pinfunction "A_B_SIDE")
			(pintype "output")
		)
		(pad "18" smd roundrect
			(at 1.937 -1.25 270)
			(size 0.825 0.25)
			(layers "F.Cu" "F.Mask" "F.Paste")
			(roundrect_rratio 0.25)
			(net 52 "/USB PD/VBUS_DISCH")
			(pinfunction "VBUS_VS_DISCH")
			(pintype "input")
		)
		(pad "19" smd roundrect
			(at 1.249 -1.938 270)
			(size 0.25 0.825)
			(layers "F.Cu" "F.Mask" "F.Paste")
			(roundrect_rratio 0.25)
			(net 54 "Net-(U1-~{ALERT})")
			(pinfunction "~{ALERT}")
			(pintype "output")
		)
		(pad "20" smd roundrect
			(at 0.748 -1.938 270)
			(size 0.25 0.825)
			(layers "F.Cu" "F.Mask" "F.Paste")
			(roundrect_rratio 0.25)
			(net 27 "POWER_OK2")
			(pinfunction "POWER_OK2")
			(pintype "output")
		)
		(pad "21" smd roundrect
			(at 0.248 -1.938 270)
			(size 0.25 0.825)
			(layers "F.Cu" "F.Mask" "F.Paste")
			(roundrect_rratio 0.25)
			(net 15 "Net-(U1-VREG_1V2)")
			(pinfunction "VREG_1V2")
			(pintype "output")
		)
		(pad "22" smd roundrect
			(at -0.25 -1.938 270)
			(size 0.25 0.825)
			(layers "F.Cu" "F.Mask" "F.Paste")
			(roundrect_rratio 0.25)
			(net 2 "GND")
			(pinfunction "VSYS")
			(pintype "power_in")
		)
		(pad "23" smd roundrect
			(at -0.75 -1.938 270)
			(size 0.25 0.825)
			(layers "F.Cu" "F.Mask" "F.Paste")
			(roundrect_rratio 0.25)
			(net 14 "Net-(U1-VREG_2V7)")
			(pinfunction "VREG_2V7")
			(pintype "output")
		)
		(pad "24" smd roundrect
			(at -1.25 -1.938 270)
			(size 0.25 0.825)
			(layers "F.Cu" "F.Mask" "F.Paste")
			(roundrect_rratio 0.25)
			(net 6 "VBUS")
			(pinfunction "VDD")
			(pintype "power_in")
		)
		(pad "25" smd rect
			(at 0 0 270)
			(size 2.1 2.1)
			(layers "F.Cu" "F.Mask")
			(net 2 "GND")
			(pinfunction "EP")
			(pintype "power_in")
		)
	)
	(footprint "antmicro-footprints:TP_SMD_0.75mm"
		(layer "F.Cu")
		(at 85.376 76.4)
		(property "Reference" "TP12"
			(at -6.858 -1.778 0)
			(layer "F.SilkS")
			(hide yes)
			(effects
				(font
					(size 0.7 0.7)
					(thickness 0.15)
				)
				(justify left bottom)
			)
		)
		(property "Value" "TP_0.75mm_SMD"
			(at 0 1.2 0)
			(layer "F.Fab")
			(effects
				(font
					(size 0.7 0.7)
					(thickness 0.15)
				)
				(justify left bottom)
			)
		)
		(property "Description" "SMT test point"
			(at 0 0 0)
			(layer "F.Fab")
			(hide yes)
			(effects
				(font
					(size 1.27 1.27)
					(thickness 0.15)
				)
			)
		)
		(property "MPN" ""
			(at 0 0 0)
			(unlocked yes)
			(layer "F.Fab")
			(hide yes)
			(effects
				(font
					(size 1 1)
					(thickness 0.15)
				)
			)
		)
		(property "Manufacturer" ""
			(at 0 0 0)
			(unlocked yes)
			(layer "F.Fab")
			(hide yes)
			(effects
				(font
					(size 1 1)
					(thickness 0.15)
				)
			)
		)
		(property "Author" "Antmicro"
			(at 0 0 0)
			(unlocked yes)
			(layer "F.Fab")
			(hide yes)
			(effects
				(font
					(size 1 1)
					(thickness 0.15)
				)
			)
		)
		(property "License" "Apache-2.0"
			(at 0 0 0)
			(unlocked yes)
			(layer "F.Fab")
			(hide yes)
			(effects
				(font
					(size 1 1)
					(thickness 0.15)
				)
			)
		)
		(sheetname "/USB PD/")
		(sheetfile "usb_pd.kicad_sch")
		(attr exclude_from_bom)
		(fp_circle
			(center 0 0)
			(end 0.475 0)
			(stroke
				(width 0.05)
				(type default)
			)
			(fill no)
			(layer "F.CrtYd")
		)
		(pad "1" smd circle
			(at 0 0)
			(size 0.75 0.75)
			(layers "F.Cu" "F.Mask")
			(net 57 "Net-(U1-GPIO)")
			(pinfunction "1")
			(pintype "passive")
		)
	)
	(footprint "antmicro-footprints:R_0402_1005Metric"
		(layer "F.Cu")
		(at 100 82.577 180)
		(descr "Resistor SMD 0402")
		(tags "resistor SMD 0402")
		(property "Reference" "R9"
			(at -1.092 -0.481 0)
			(layer "F.SilkS")
			(effects
				(font
					(size 0.7 0.7)
					(thickness 0.15)
				)
				(justify left bottom)
			)
		)
		(property "Value" "R_158k_0402"
			(at -1.011843 1.772047 0)
			(layer "F.Fab")
			(effects
				(font
					(size 0.7 0.7)
					(thickness 0.15)
				)
				(justify right bottom)
			)
		)
		(property "Datasheet" "https://www.bourns.com/docs/product-datasheets/cr.pdf"
			(at 0 0 180)
			(layer "F.Fab")
			(hide yes)
			(effects
				(font
					(size 1.27 1.27)
					(thickness 0.15)
				)
			)
		)
		(property "Description" "SMD Chip Resistor, 158 kohm, ± 1%, 100 mW, 0402 [1005 Metric], Thick Film, Precision"
			(at 0 0 180)
			(layer "F.Fab")
			(hide yes)
			(effects
				(font
					(size 1.27 1.27)
					(thickness 0.15)
				)
			)
		)
		(property "MPN" "CR0402-FX-1583GLF"
			(at 0 0 180)
			(unlocked yes)
			(layer "F.Fab")
			(hide yes)
			(effects
				(font
					(size 1 1)
					(thickness 0.15)
				)
			)
		)
		(property "Manufacturer" "Bourns"
			(at 0 0 180)
			(unlocked yes)
			(layer "F.Fab")
			(hide yes)
			(effects
				(font
					(size 1 1)
					(thickness 0.15)
				)
			)
		)
		(property "License" "Apache-2.0"
			(at 0 0 180)
			(unlocked yes)
			(layer "F.Fab")
			(hide yes)
			(effects
				(font
					(size 1 1)
					(thickness 0.15)
				)
			)
		)
		(property "Author" "Antmicro"
			(at 0 0 180)
			(unlocked yes)
			(layer "F.Fab")
			(hide yes)
			(effects
				(font
					(size 1 1)
					(thickness 0.15)
				)
			)
		)
		(property "Val" "158k"
			(at 0 0 180)
			(unlocked yes)
			(layer "F.Fab")
			(hide yes)
			(effects
				(font
					(size 1 1)
					(thickness 0.15)
				)
			)
		)
		(property "Tolerance" "1%"
			(at 0 0 180)
			(unlocked yes)
			(layer "F.Fab")
			(hide yes)
			(effects
				(font
					(size 1 1)
					(thickness 0.15)
				)
			)
		)
		(sheetname "/DC-DC Converters/")
		(sheetfile "dc-dc_converters.kicad_sch")
		(attr smd)
		(fp_rect
			(start -0.925 -0.47)
			(end 0.925 0.47)
			(stroke
				(width 0.05)
				(type default)
			)
			(fill no)
			(layer "F.CrtYd")
		)
		(fp_rect
			(start -0.5 -0.25)
			(end 0.5 0.25)
			(stroke
				(width 0.15)
				(type solid)
			)
			(fill no)
			(layer "F.Fab")
		)
		(pad "1" smd roundrect
			(at -0.48 0 180)
			(size 0.59 0.64)
			(layers "F.Cu" "F.Mask" "F.Paste")
			(roundrect_rratio 0.25)
			(net 2 "GND")
			(pintype "passive")
		)
		(pad "2" smd roundrect
			(at 0.48 0 180)
			(size 0.59 0.64)
			(layers "F.Cu" "F.Mask" "F.Paste")
			(roundrect_rratio 0.25)
			(net 46 "/DC-DC Converters/12V_FSW")
			(pintype "passive")
		)
	)
	(footprint "antmicro-footprints:R_0603_1608Metric"
		(layer "F.Cu")
		(at 82.45 79.45 90)
		(descr "Resistor SMD 0603")
		(tags "resistor SMD 0603")
		(property "Reference" "R3"
			(at 1.218 -0.662 180)
			(layer "F.SilkS")
			(effects
				(font
					(size 0.7 0.7)
					(thickness 0.15)
				)
				(justify left bottom)
			)
		)
		(property "Value" "R_4k7_0603"
			(at 0 1.6 90)
			(layer "F.Fab")
			(effects
				(font
					(size 0.7 0.7)
					(thickness 0.15)
				)
				(justify left bottom)
			)
		)
		(property "Datasheet" "https://www.bourns.com/docs/product-datasheets/cr.pdf"
			(at 0 0 90)
			(layer "F.Fab")
			(hide yes)
			(effects
				(font
					(size 1.27 1.27)
					(thickness 0.15)
				)
			)
		)
		(property "Description" "SMD Chip Resistor, 4.7 kohm, ± 1%, 100 mW, 0603 [1608 Metric], Thick Film, General Purpose"
			(at 0 0 90)
			(layer "F.Fab")
			(hide yes)
			(effects
				(font
					(size 1.27 1.27)
					(thickness 0.15)
				)
			)
		)
		(property "MPN" "CR0603-FX-4701ELF"
			(at 0 0 90)
			(unlocked yes)
			(layer "F.Fab")
			(hide yes)
			(effects
				(font
					(size 1 1)
					(thickness 0.15)
				)
			)
		)
		(property "Manufacturer" "Bourns"
			(at 0 0 90)
			(unlocked yes)
			(layer "F.Fab")
			(hide yes)
			(effects
				(font
					(size 1 1)
					(thickness 0.15)
				)
			)
		)
		(property "License" "Apache-2.0"
			(at 0 0 90)
			(unlocked yes)
			(layer "F.Fab")
			(hide yes)
			(effects
				(font
					(size 1 1)
					(thickness 0.15)
				)
			)
		)
		(property "Author" "Antmicro"
			(at 0 0 90)
			(unlocked yes)
			(layer "F.Fab")
			(hide yes)
			(effects
				(font
					(size 1 1)
					(thickness 0.15)
				)
			)
		)
		(property "Val" "4k7"
			(at 0 0 90)
			(unlocked yes)
			(layer "F.Fab")
			(hide yes)
			(effects
				(font
					(size 1 1)
					(thickness 0.15)
				)
			)
		)
		(property "Tolerance" "1%"
			(at 0 0 90)
			(unlocked yes)
			(layer "F.Fab")
			(hide yes)
			(effects
				(font
					(size 1 1)
					(thickness 0.15)
				)
			)
		)
		(sheetname "/USB PD/")
		(sheetfile "usb_pd.kicad_sch")
		(attr smd)
		(fp_line
			(start -0.15 -0.4)
			(end 0.15 -0.4)
			(stroke
				(width 0.15)
				(type solid)
			)
			(layer "F.SilkS")
		)
		(fp_line
			(start -0.15 0.4)
			(end 0.15 0.4)
			(stroke
				(width 0.15)
				(type solid)
			)
			(layer "F.SilkS")
		)
		(fp_rect
			(start -1.25 -0.65)
			(end 1.25 0.65)
			(stroke
				(width 0.05)
				(type solid)
			)
			(fill no)
			(layer "F.CrtYd")
		)
		(fp_rect
			(start -0.8 -0.4)
			(end 0.8 0.4)
			(stroke
				(width 0.15)
				(type solid)
			)
			(fill no)
			(layer "F.Fab")
		)
		(pad "1" smd roundrect
			(at -0.7 0 90)
			(size 0.8 1)
			(layers "F.Cu" "F.Mask" "F.Paste")
			(roundrect_rratio 0.2)
			(net 3 "VCC")
			(pintype "passive")
		)
		(pad "2" smd roundrect
			(at 0.7 0 90)
			(size 0.8 1)
			(layers "F.Cu" "F.Mask" "F.Paste")
			(roundrect_rratio 0.2)
			(net 41 "Net-(U1-DISCH)")
			(pintype "passive")
		)
	)
)
